# TIMECARD (Time Appliance Project (Time Card)) — schematic netlist excerpt (pin names and nets, part order shuffled) for the footprints in the layout excerpt that follows; sources: Cadence DE-HDL packaged netlist, KiCad conversion of R4006-B0001-02_R01.brd

TP200  TP_PIONT  pkg TP010CT020B030_PTH  page 25 : \1\ = IO_L20N_35

DS17  LED_4P_V14  pkg SMC_DS4_098X039  page 26
  \1\  = UNNAMED_14_LED4PV14_I268_1
  \2\  = XP3R3V_FPGA
  \3\  = UNNAMED_14_LED4PV14_I268_3
  \4\  = UNNAMED_14_LED4PV14_I268_4

(kicad_pcb
	(version 20260206)
	(generator "pcbnew")
	(generator_version "10.0")
	(general
		(thickness 1.6)
		(legacy_teardrops no)
	)
	(paper "A4")
	(title_block
		(title "timecard-production-celestica-r4006 — R4006-B0001-02_R01.brd")
		(comment 1 "Time Appliance Project (Time Card) / footprints 145-146 of 1113")
	)
	(layers
		(0 "F.Cu" signal "TOP")
		(4 "In1.Cu" signal "L02_GND1")
		(6 "In2.Cu" signal "L03_SIG1")
		(8 "In3.Cu" signal "L04_GND2")
		(10 "In4.Cu" signal "L05_VCC1")
		(12 "In5.Cu" signal "L06_VCC2")
		(14 "In6.Cu" signal "L07_GND3")
		(16 "In7.Cu" signal "L08_SIG2")
		(18 "In8.Cu" signal "L09_GND4")
		(2 "B.Cu" signal "BOTTOM")
		(9 "F.Adhes" user "F.Adhesive")
		(11 "B.Adhes" user "B.Adhesive")
		(13 "F.Paste" user "Package Geometry/Pastemask Top")
		(15 "B.Paste" user "Package Geometry/Pastemask Bottom")
		(5 "F.SilkS" user "Ref Des/Silkscreen Top")
		(7 "B.SilkS" user "Ref Des/Silkscreen Bottom")
		(1 "F.Mask" user "Board Geometry/Soldermask Top")
		(3 "B.Mask" user "Board Geometry/Soldermask Bottom")
		(17 "Dwgs.User" user "User.Drawings")
		(19 "Cmts.User" user "User.Comments")
		(21 "Eco1.User" user "User.Eco1")
		(23 "Eco2.User" user "User.Eco2")
		(25 "Edge.Cuts" user "Board Geometry/Outline")
		(27 "Margin" user)
		(31 "F.CrtYd" user "Package Geometry/Place Bound Top")
		(29 "B.CrtYd" user "Package Geometry/Place Bound Bottom")
		(35 "F.Fab" user "Ref Des/Assembly Top")
		(33 "B.Fab" user "Ref Des/Assembly Bottom")
	)
	(footprint ""
		(layer "F.Cu")
		(at 1.500124 -53.600096 90)
		(property "Reference" "DS17"
			(at 2.875534 0.785876 0)
			(unlocked yes)
			(layer "F.SilkS")
			(effects
				(font
					(size 0.7874 0.5842)
					(thickness 0.1524)
				)
			)
		)
		(property "Value" ""
			(at 0 0 90)
			(layer "F.Fab")
			(effects
				(font
					(size 1.27 1.27)
				)
			)
		)
		(property "User Part Number" "PARTNUM*"
			(at 0.015494 4.486402 90)
			(unlocked yes)
			(layer "Cmts.User")
			(hide yes)
			(effects
				(font
					(size 0.7874 0.5842)
					(thickness 0.1524)
				)
			)
		)
		(property "Device Type" "LED_4P_V14-G170-10189-01"
			(at 0.015494 3.292602 90)
			(unlocked yes)
			(layer "F.Fab")
			(hide yes)
			(effects
				(font
					(size 0.7874 0.5842)
					(thickness 0.1524)
				)
			)
		)
		(duplicate_pad_numbers_are_jumpers no)
		(fp_line
			(start 1.378966 -0.829056)
			(end -1.378966 -0.829056)
			(stroke
				(width 0.1)
				(type default)
			)
			(layer "F.SilkS")
		)
		(fp_line
			(start -1.378966 -0.829056)
			(end -1.378966 -0.452628)
			(stroke
				(width 0.1)
				(type default)
			)
			(layer "F.SilkS")
		)
		(fp_line
			(start 1.998218 -0.452628)
			(end 1.378966 -0.452628)
			(stroke
				(width 0.1)
				(type default)
			)
			(layer "F.SilkS")
		)
		(fp_line
			(start 1.378966 -0.452628)
			(end 1.378966 -0.829056)
			(stroke
				(width 0.1)
				(type default)
			)
			(layer "F.SilkS")
		)
		(fp_line
			(start -1.378966 -0.452628)
			(end -1.998218 -0.452628)
			(stroke
				(width 0.1)
				(type default)
			)
			(layer "F.SilkS")
		)
		(fp_line
			(start -1.998218 -0.452628)
			(end -1.998218 1.103884)
			(stroke
				(width 0.1)
				(type default)
			)
			(layer "F.SilkS")
		)
		(fp_line
			(start 1.998218 1.103884)
			(end 1.998218 -0.452628)
			(stroke
				(width 0.1)
				(type default)
			)
			(layer "F.SilkS")
		)
		(fp_line
			(start -1.998218 1.103884)
			(end 1.998218 1.103884)
			(stroke
				(width 0.1)
				(type default)
			)
			(layer "F.SilkS")
		)
		(fp_poly
			(pts
				(xy 0.918464 -1.698498) (xy 1.223264 -1.46939) (xy 0.994664 -1.46939) (xy 0.994664 -1.24079) (xy 0.842264 -1.24079)
				(xy 0.842264 -1.46939) (xy 0.613664 -1.46939)
			)
			(stroke
				(width 0)
				(type default)
			)
			(fill yes)
			(layer "F.SilkS")
		)
		(fp_poly
			(pts
				(xy -0.73406 -1.677416) (xy -0.42926 -1.448308) (xy -0.65786 -1.448308) (xy -0.65786 -1.219708)
				(xy -0.81026 -1.219708) (xy -0.81026 -1.448308) (xy -1.03886 -1.448308)
			)
			(stroke
				(width 0)
				(type default)
			)
			(fill yes)
			(layer "F.SilkS")
		)
		(fp_poly
			(pts
				(xy -2.252218 1.357884) (xy -2.252218 -0.706628) (xy -1.632966 -0.706628) (xy -1.632966 -1.083056)
				(xy 1.632966 -1.083056) (xy 1.632966 -0.706628) (xy 2.252218 -0.706628) (xy 2.252218 1.357884)
			)
			(stroke
				(width 0)
				(type default)
			)
			(fill no)
			(layer "F.CrtYd")
		)
		(fp_line
			(start 1.124966 -0.575056)
			(end -1.124966 -0.575056)
			(stroke
				(width 0.1)
				(type default)
			)
			(layer "F.Fab")
		)
		(fp_line
			(start -1.124966 -0.575056)
			(end -1.124966 -0.075184)
			(stroke
				(width 0.1)
				(type default)
			)
			(layer "F.Fab")
		)
		(fp_line
			(start 1.325118 -0.075184)
			(end 1.124966 -0.075184)
			(stroke
				(width 0.1)
				(type default)
			)
			(layer "F.Fab")
		)
		(fp_line
			(start 1.124966 -0.075184)
			(end 1.124966 -0.575056)
			(stroke
				(width 0.1)
				(type default)
			)
			(layer "F.Fab")
		)
		(fp_line
			(start -1.124966 -0.075184)
			(end -1.325118 -0.075184)
			(stroke
				(width 0.1)
				(type default)
			)
			(layer "F.Fab")
		)
		(fp_line
			(start -1.325118 -0.075184)
			(end -1.325118 0.574802)
			(stroke
				(width 0.1)
				(type default)
			)
			(layer "F.Fab")
		)
		(fp_line
			(start 1.325118 0.574802)
			(end 1.325118 -0.075184)
			(stroke
				(width 0.1)
				(type default)
			)
			(layer "F.Fab")
		)
		(fp_line
			(start -1.325118 0.574802)
			(end 1.325118 0.574802)
			(stroke
				(width 0.1)
				(type default)
			)
			(layer "F.Fab")
		)
		(fp_poly
			(pts
				(xy 0.918464 -1.698498) (xy 1.223264 -1.46939) (xy 0.994664 -1.46939) (xy 0.994664 -1.24079) (xy 0.842264 -1.24079)
				(xy 0.842264 -1.46939) (xy 0.613664 -1.46939)
			)
			(stroke
				(width 0)
				(type default)
			)
			(fill yes)
			(layer "F.Fab")
		)
		(fp_poly
			(pts
				(xy -0.73406 -1.677416) (xy -0.42926 -1.448308) (xy -0.65786 -1.448308) (xy -0.65786 -1.219708)
				(xy -0.81026 -1.219708) (xy -0.81026 -1.448308) (xy -1.03886 -1.448308)
			)
			(stroke
				(width 0)
				(type default)
			)
			(fill yes)
			(layer "F.Fab")
		)
		(fp_text user "1"
			(at -2.37617 0.376936 90)
			(unlocked yes)
			(layer "F.SilkS")
			(effects
				(font
					(size 0.7874 0.5842)
					(thickness 0.1524)
				)
			)
		)
		(fp_text user "2"
			(at -1.053846 1.420876 0)
			(unlocked yes)
			(layer "F.SilkS")
			(effects
				(font
					(size 0.635 0.4064)
					(thickness 0.1524)
				)
			)
		)
		(fp_text user "3"
			(at 1.486154 1.547876 0)
			(unlocked yes)
			(layer "F.SilkS")
			(effects
				(font
					(size 0.635 0.4064)
					(thickness 0.1524)
				)
			)
		)
		(fp_text user "4"
			(at 2.03835 1.166876 0)
			(unlocked yes)
			(layer "F.Fab")
			(effects
				(font
					(size 0.7874 0.5842)
					(thickness 0.1524)
				)
			)
		)
		(fp_text user "3"
			(at 1.02235 1.166876 0)
			(unlocked yes)
			(layer "F.Fab")
			(effects
				(font
					(size 0.7874 0.5842)
					(thickness 0.1524)
				)
			)
		)
		(fp_text user "2"
			(at 0.00635 1.166876 0)
			(unlocked yes)
			(layer "F.Fab")
			(effects
				(font
					(size 0.7874 0.5842)
					(thickness 0.1524)
				)
			)
		)
		(fp_text user "1"
			(at -1.061466 1.166876 0)
			(unlocked yes)
			(layer "F.Fab")
			(effects
				(font
					(size 0.7874 0.5842)
					(thickness 0.1524)
				)
			)
		)
		(pad "1" smd rect
			(at -1.325118 0.245872 90)
			(size 0.8382 0.889)
			(layers "F.Cu" "F.Mask" "F.Paste")
			(net "UNNAMED_14_LED4PV14_I268_1")
		)
		(pad "2" smd rect
			(at -0.424942 0.595884 90)
			(size 0.4572 0.508)
			(layers "F.Cu" "F.Mask" "F.Paste")
			(net "XP3R3V_FPGA")
		)
		(pad "3" smd rect
			(at 0.424942 0.595884 90)
			(size 0.4572 0.508)
			(layers "F.Cu" "F.Mask" "F.Paste")
			(net "UNNAMED_14_LED4PV14_I268_3")
		)
		(pad "4" smd rect
			(at 1.325118 0.245872 90)
			(size 0.8382 0.889)
			(layers "F.Cu" "F.Mask" "F.Paste")
			(net "UNNAMED_14_LED4PV14_I268_4")
		)
	)
	(footprint ""
		(layer "F.Cu")
		(at 107.188 -31.369 90)
		(property "Reference" "TP200"
			(at -3.0988 0.15875 90)
			(unlocked yes)
			(layer "F.SilkS")
			(effects
				(font
					(size 0.635 0.4064)
					(thickness 0.1524)
				)
				(justify left)
			)
		)
		(property "Value" ""
			(at 0 0 90)
			(layer "F.Fab")
			(effects
				(font
					(size 1.27 1.27)
				)
			)
		)
		(property "Device Type" "TP_PIONT-TP010CT020B030_PTH-TPA"
			(at -1.341882 0.996696 90)
			(unlocked yes)
			(layer "F.Fab")
			(hide yes)
			(effects
				(font
					(size 0.7874 0.5842)
					(thickness 0.1524)
				)
				(justify left)
			)
		)
		(duplicate_pad_numbers_are_jumpers no)
		(fp_poly
			(pts
				(arc
					(start 0 0.889)
					(mid 0 -0.889)
					(end 0 0.889)
				)
			)
			(stroke
				(width 0)
				(type default)
			)
			(fill no)
			(layer "B.CrtYd")
		)
		(fp_poly
			(pts
				(arc
					(start 0 0.889)
					(mid 0 -0.889)
					(end 0 0.889)
				)
			)
			(stroke
				(width 0)
				(type default)
			)
			(fill no)
			(layer "F.CrtYd")
		)
		(pad "1" thru_hole circle
			(at 0 0 90)
			(size 0.508 0.508)
			(drill 0.254)
			(layers "*.Cu" "*.Mask")
			(remove_unused_layers no)
			(net "IO_L20N_35")
			(clearance 0.1016)
			(padstack
				(mode front_inner_back)
				(layer "Inner"
					(shape circle)
					(size 0.508 0.508)
					(clearance 0.1016)
				)
				(layer "B.Cu"
					(shape circle)
					(size 0.762 0.762)
					(clearance -0.0254)
				)
			)
		)
	)
)
